(kicad_pcb
	(version 20211014)
	(generator pcbnew)
	(general
    (thickness 1.6)
  )
	(paper "A4")
	(title_block
    (title "SA800U (Snapdragon 845) Baseboard")
    (date "2023-10-19")
    (rev "1.0.3")
    (company "Antmicro Ltd.")
    (comment 1 "www.antmicro.com")
		(comment 9 "footprints 298-305 of 589")
	)
	(layers
    (0 "F.Cu" signal)
    (1 "In1.Cu" power)
    (2 "In2.Cu" signal)
    (3 "In3.Cu" signal)
    (4 "In4.Cu" power)
    (31 "B.Cu" signal)
    (32 "B.Adhes" user "B.Adhesive")
    (33 "F.Adhes" user "F.Adhesive")
    (34 "B.Paste" user)
    (35 "F.Paste" user)
    (36 "B.SilkS" user "B.Silkscreen")
    (37 "F.SilkS" user "F.Silkscreen")
    (38 "B.Mask" user)
    (39 "F.Mask" user)
    (40 "Dwgs.User" user "User.Drawings")
    (41 "Cmts.User" user "User.Comments")
    (42 "Eco1.User" user "User.Eco1")
    (43 "Eco2.User" user "User.Eco2")
    (44 "Edge.Cuts" user)
    (45 "Margin" user)
    (46 "B.CrtYd" user "B.Courtyard")
    (47 "F.CrtYd" user "F.Courtyard")
    (48 "B.Fab" user)
    (49 "F.Fab" user)
  )
	(footprint "sa800u-baseboard-hw-footprints:R_0402_1005Metric" (layer "B.Cu")
    (tedit 5FD9C158)
    (at 128.8 103.6)
    (descr "Resistor SMD 0402")
    (tags "resistor SMD 0402")
    (property "Author" "Antmicro")
    (property "Current" "1A")
    (property "License" "Apache-2.0")
    (property "MPN" "ERJ2GE0R00X")
    (property "Manufacturer" "Panasonic")
    (property "Sheetfile" "other-interfaces.kicad_sch")
    (property "Sheetname" "Other Interfaces")
    (property "Tolerance" "")
    (property "Val" "0R")
    (attr smd)
    (fp_text reference "R99" (at -0.77 0.43 180) (layer "B.SilkS")
      (effects (font (size 0.7 0.7) (thickness 0.15)) (justify left bottom mirror))
    )
    (fp_text value "R_0R_0402" (at 0 -1.4 180) (layer "B.Fab")
      (effects (font (size 0.7 0.7) (thickness 0.15)) (justify left bottom mirror))
    )
    (fp_text user "License: Apache-2.0" (at -0.95 -5.169 180) (layer "B.Fab") hide
      (effects (font (size 0.7 0.7) (thickness 0.15)) (justify left bottom mirror))
    )
    (fp_text user "${REFERENCE}" (at -0.95 -3.168 180) (layer "B.Fab") hide
      (effects (font (size 0.7 0.7) (thickness 0.15)) (justify left bottom mirror))
    )
    (fp_text user "Author: Antmicro" (at -0.95 -4.169 180) (layer "B.Fab") hide
      (effects (font (size 0.7 0.7) (thickness 0.15)) (justify left bottom mirror))
    )
    (fp_rect (start -0.93 0.47) (end 0.93 -0.47) (layer "B.CrtYd") (width 0.05) (fill none))
    (fp_rect (start -0.5 0.25) (end 0.5 -0.25) (layer "B.Fab") (width 0.15) (fill none))
    (pad "1" smd roundrect (at -0.485 0) (size 0.59 0.64) (layers "B.Cu" "B.Paste" "B.Mask") (roundrect_rratio 0.25)
      (net 106 "SD_LDO21A") (pintype "passive"))
    (pad "2" smd roundrect (at 0.485 0) (size 0.59 0.64) (layers "B.Cu" "B.Paste" "B.Mask") (roundrect_rratio 0.25)
      (net 227 "/Other Interfaces/SD_VDD_R") (pintype "passive"))
  )
	(footprint "sa800u-baseboard-hw-footprints:C_0402_1005Metric" (layer "B.Cu")
    (tedit 616D63CF)
    (at 132.6 105.95 180)
    (descr "Capacitor SMD 0402")
    (tags "capacitor SMD 0402")
    (property "Author" "Antmicro")
    (property "Dielectric" "X5R")
    (property "License" "Apache-2.0")
    (property "MPN" "GRM155R61H104KE14D")
    (property "Manufacturer" "Murata")
    (property "Sheetfile" "hdmi-converter.kicad_sch")
    (property "Sheetname" "HDMI converter")
    (property "Val" "100n")
    (property "Voltage" "50V")
    (attr smd)
    (fp_text reference "C44" (at -1.97 0.54) (layer "B.SilkS")
      (effects (font (size 0.7 0.7) (thickness 0.15)) (justify left bottom mirror))
    )
    (fp_text value "C_100n_0402" (at 0 -1.4) (layer "B.Fab")
      (effects (font (size 0.7 0.7) (thickness 0.15)) (justify left bottom mirror))
    )
    (fp_text user "Author: Antmicro" (at -0.932 -4.17) (layer "B.Fab") hide
      (effects (font (size 0.7 0.7) (thickness 0.15)) (justify left bottom mirror))
    )
    (fp_text user "${REFERENCE}" (at -0.932 -3.168) (layer "B.Fab") hide
      (effects (font (size 0.7 0.7) (thickness 0.15)) (justify left bottom mirror))
    )
    (fp_text user "License: Apache-2.0" (at -0.932 -5.17) (layer "B.Fab") hide
      (effects (font (size 0.7 0.7) (thickness 0.15)) (justify left bottom mirror))
    )
    (fp_rect (start -0.94 0.47) (end 0.94 -0.47) (layer "B.CrtYd") (width 0.05) (fill none))
    (fp_rect (start -0.499 0.249) (end 0.499 -0.249) (layer "B.Fab") (width 0.15) (fill none))
    (pad "1" smd roundrect (at -0.484 0 180) (size 0.59 0.64) (layers "B.Cu" "B.Paste" "B.Mask") (roundrect_rratio 0.25)
      (net 132 "VREG_S4A_1V8") (pintype "passive"))
    (pad "2" smd roundrect (at 0.484 0 180) (size 0.59 0.64) (layers "B.Cu" "B.Paste" "B.Mask") (roundrect_rratio 0.25)
      (net 1 "GND") (pintype "passive"))
  )
	(footprint "sa800u-baseboard-hw-footprints:C_0402_1005Metric" (layer "B.Cu")
    (tedit 616D63CF)
    (at 134.5 105.95)
    (descr "Capacitor SMD 0402")
    (tags "capacitor SMD 0402")
    (property "Author" "Antmicro")
    (property "Dielectric" "X5R")
    (property "License" "Apache-2.0")
    (property "MPN" "GRM155R61H104KE14D")
    (property "Manufacturer" "Murata")
    (property "Sheetfile" "hdmi-converter.kicad_sch")
    (property "Sheetname" "HDMI converter")
    (property "Val" "100n")
    (property "Voltage" "50V")
    (attr smd)
    (fp_text reference "C54" (at 2.16 -0.54 180) (layer "B.SilkS")
      (effects (font (size 0.7 0.7) (thickness 0.15)) (justify left bottom mirror))
    )
    (fp_text value "C_100n_0402" (at 0 -1.4 180) (layer "B.Fab")
      (effects (font (size 0.7 0.7) (thickness 0.15)) (justify left bottom mirror))
    )
    (fp_text user "Author: Antmicro" (at -0.932 -4.17 180) (layer "B.Fab") hide
      (effects (font (size 0.7 0.7) (thickness 0.15)) (justify left bottom mirror))
    )
    (fp_text user "License: Apache-2.0" (at -0.932 -5.17 180) (layer "B.Fab") hide
      (effects (font (size 0.7 0.7) (thickness 0.15)) (justify left bottom mirror))
    )
    (fp_text user "${REFERENCE}" (at -0.932 -3.168 180) (layer "B.Fab") hide
      (effects (font (size 0.7 0.7) (thickness 0.15)) (justify left bottom mirror))
    )
    (fp_rect (start -0.94 0.47) (end 0.94 -0.47) (layer "B.CrtYd") (width 0.05) (fill none))
    (fp_rect (start -0.499 0.249) (end 0.499 -0.249) (layer "B.Fab") (width 0.15) (fill none))
    (pad "1" smd roundrect (at -0.484 0) (size 0.59 0.64) (layers "B.Cu" "B.Paste" "B.Mask") (roundrect_rratio 0.25)
      (net 131 "3V3_SYS") (pintype "passive"))
    (pad "2" smd roundrect (at 0.484 0) (size 0.59 0.64) (layers "B.Cu" "B.Paste" "B.Mask") (roundrect_rratio 0.25)
      (net 1 "GND") (pintype "passive"))
  )
	(footprint "sa800u-baseboard-hw-footprints:C_0402_1005Metric" (layer "B.Cu")
    (tedit 616D63CF)
    (at 140.34 91.44 180)
    (descr "Capacitor SMD 0402")
    (tags "capacitor SMD 0402")
    (property "Author" "Antmicro")
    (property "Dielectric" "")
    (property "License" "Apache-2.0")
    (property "MPN" "C1005X6S1A105K050BC")
    (property "Manufacturer" "TDK")
    (property "Sheetfile" "m2.kicad_sch")
    (property "Sheetname" "M2")
    (property "Val" "1u")
    (property "Voltage" "")
    (attr smd)
    (fp_text reference "C111" (at -0.82 0.61) (layer "B.SilkS")
      (effects (font (size 0.7 0.7) (thickness 0.15)) (justify left bottom mirror))
    )
    (fp_text value "C_1u_0402" (at 0 -1.4) (layer "B.Fab")
      (effects (font (size 0.7 0.7) (thickness 0.15)) (justify left bottom mirror))
    )
    (fp_text user "${REFERENCE}" (at -0.932 -3.168) (layer "B.Fab") hide
      (effects (font (size 0.7 0.7) (thickness 0.15)) (justify left bottom mirror))
    )
    (fp_text user "License: Apache-2.0" (at -0.932 -5.17) (layer "B.Fab") hide
      (effects (font (size 0.7 0.7) (thickness 0.15)) (justify left bottom mirror))
    )
    (fp_text user "Author: Antmicro" (at -0.932 -4.17) (layer "B.Fab") hide
      (effects (font (size 0.7 0.7) (thickness 0.15)) (justify left bottom mirror))
    )
    (fp_rect (start -0.94 0.47) (end 0.94 -0.47) (layer "B.CrtYd") (width 0.05) (fill none))
    (fp_rect (start -0.499 0.249) (end 0.499 -0.249) (layer "B.Fab") (width 0.15) (fill none))
    (pad "1" smd roundrect (at -0.484 0 180) (size 0.59 0.64) (layers "B.Cu" "B.Paste" "B.Mask") (roundrect_rratio 0.25)
      (net 131 "3V3_SYS") (pintype "passive"))
    (pad "2" smd roundrect (at 0.484 0 180) (size 0.59 0.64) (layers "B.Cu" "B.Paste" "B.Mask") (roundrect_rratio 0.25)
      (net 1 "GND") (pintype "passive"))
  )
	(footprint "sa800u-baseboard-hw-footprints:C_0402_1005Metric" (layer "B.Cu")
    (tedit 616D63CF)
    (at 140.345 105.6 180)
    (descr "Capacitor SMD 0402")
    (tags "capacitor SMD 0402")
    (property "Author" "Antmicro")
    (property "Dielectric" "")
    (property "License" "Apache-2.0")
    (property "MPN" "C1005X6S1A105K050BC")
    (property "Manufacturer" "TDK")
    (property "Sheetfile" "m2.kicad_sch")
    (property "Sheetname" "M2")
    (property "Val" "1u")
    (property "Voltage" "")
    (attr smd)
    (fp_text reference "C112" (at 0.81 -0.35) (layer "B.SilkS")
      (effects (font (size 0.7 0.7) (thickness 0.15)) (justify left bottom mirror))
    )
    (fp_text value "C_1u_0402" (at 0 -1.4) (layer "B.Fab")
      (effects (font (size 0.7 0.7) (thickness 0.15)) (justify left bottom mirror))
    )
    (fp_text user "Author: Antmicro" (at -0.932 -4.17) (layer "B.Fab") hide
      (effects (font (size 0.7 0.7) (thickness 0.15)) (justify left bottom mirror))
    )
    (fp_text user "License: Apache-2.0" (at -0.932 -5.17) (layer "B.Fab") hide
      (effects (font (size 0.7 0.7) (thickness 0.15)) (justify left bottom mirror))
    )
    (fp_text user "${REFERENCE}" (at -0.932 -3.168) (layer "B.Fab") hide
      (effects (font (size 0.7 0.7) (thickness 0.15)) (justify left bottom mirror))
    )
    (fp_rect (start -0.94 0.47) (end 0.94 -0.47) (layer "B.CrtYd") (width 0.05) (fill none))
    (fp_rect (start -0.499 0.249) (end 0.499 -0.249) (layer "B.Fab") (width 0.15) (fill none))
    (pad "1" smd roundrect (at -0.484 0 180) (size 0.59 0.64) (layers "B.Cu" "B.Paste" "B.Mask") (roundrect_rratio 0.25)
      (net 131 "3V3_SYS") (pintype "passive"))
    (pad "2" smd roundrect (at 0.484 0 180) (size 0.59 0.64) (layers "B.Cu" "B.Paste" "B.Mask") (roundrect_rratio 0.25)
      (net 1 "GND") (pintype "passive"))
  )
	(footprint "sa800u-baseboard-hw-footprints:C_0402_1005Metric" (layer "B.Cu")
    (tedit 616D63CF)
    (at 140.34 109.05 180)
    (descr "Capacitor SMD 0402")
    (tags "capacitor SMD 0402")
    (property "Author" "Antmicro")
    (property "Dielectric" "")
    (property "License" "Apache-2.0")
    (property "MPN" "C1005X6S1A105K050BC")
    (property "Manufacturer" "TDK")
    (property "Sheetfile" "m2.kicad_sch")
    (property "Sheetname" "M2")
    (property "Val" "1u")
    (property "Voltage" "")
    (attr smd)
    (fp_text reference "C114" (at -1.01 -1.31) (layer "B.SilkS")
      (effects (font (size 0.7 0.7) (thickness 0.15)) (justify left bottom mirror))
    )
    (fp_text value "C_1u_0402" (at 0 -1.4) (layer "B.Fab")
      (effects (font (size 0.7 0.7) (thickness 0.15)) (justify left bottom mirror))
    )
    (fp_text user "Author: Antmicro" (at -0.932 -4.17) (layer "B.Fab") hide
      (effects (font (size 0.7 0.7) (thickness 0.15)) (justify left bottom mirror))
    )
    (fp_text user "License: Apache-2.0" (at -0.932 -5.17) (layer "B.Fab") hide
      (effects (font (size 0.7 0.7) (thickness 0.15)) (justify left bottom mirror))
    )
    (fp_text user "${REFERENCE}" (at -0.932 -3.168) (layer "B.Fab") hide
      (effects (font (size 0.7 0.7) (thickness 0.15)) (justify left bottom mirror))
    )
    (fp_rect (start -0.94 0.47) (end 0.94 -0.47) (layer "B.CrtYd") (width 0.05) (fill none))
    (fp_rect (start -0.499 0.249) (end 0.499 -0.249) (layer "B.Fab") (width 0.15) (fill none))
    (pad "1" smd roundrect (at -0.484 0 180) (size 0.59 0.64) (layers "B.Cu" "B.Paste" "B.Mask") (roundrect_rratio 0.25)
      (net 131 "3V3_SYS") (pintype "passive"))
    (pad "2" smd roundrect (at 0.484 0 180) (size 0.59 0.64) (layers "B.Cu" "B.Paste" "B.Mask") (roundrect_rratio 0.25)
      (net 1 "GND") (pintype "passive"))
  )
	(footprint "sa800u-baseboard-hw-footprints:SC70-3" (layer "B.Cu")
    (tedit 615FF353)
    (at 118.745 113.6)
    (property "Author" "Antmicro")
    (property "License" "Apache-2.0")
    (property "MPN" "BSS138PW")
    (property "Manufacturer" "Nexperia")
    (property "Sheetfile" "hdmi-converter.kicad_sch")
    (property "Sheetname" "HDMI converter")
    (attr smd)
    (fp_text reference "Q1" (at 0.48 -1.42 180) (layer "B.SilkS")
      (effects (font (size 0.7 0.7) (thickness 0.15)) (justify left bottom mirror))
    )
    (fp_text value "BSS138PW" (at 0 -2.3 180) (layer "B.Fab")
      (effects (font (size 0.7 0.7) (thickness 0.15)) (justify left bottom mirror))
    )
    (fp_text user "${REFERENCE}" (at -1.45 -4.783 180) (layer "B.Fab") hide
      (effects (font (size 0.7 0.7) (thickness 0.15)) (justify left bottom mirror))
    )
    (fp_text user "License: Apache-2.0" (at -1.45 -6.782 180) (layer "B.Fab") hide
      (effects (font (size 0.7 0.7) (thickness 0.15)) (justify left bottom mirror))
    )
    (fp_text user "Author: Antmicro" (at -1.45 -5.782 180) (layer "B.Fab") hide
      (effects (font (size 0.7 0.7) (thickness 0.15)) (justify left bottom mirror))
    )
    (fp_line (start 0.627 0.6) (end 0.627 0.999) (layer "B.SilkS") (width 0.15))
    (fp_line (start -0.3 -1) (end 0.627 -1.001) (layer "B.SilkS") (width 0.15))
    (fp_line (start 0.627 -0.6) (end 0.627 -1.001) (layer "B.SilkS") (width 0.15))
    (fp_line (start -0.3 1) (end 0.627 0.999) (layer "B.SilkS") (width 0.15))
    (fp_line (start -1.4 -1) (end -1.4 1) (layer "B.CrtYd") (width 0.05))
    (fp_line (start 0.9 -0.4) (end 0.9 -1.3) (layer "B.CrtYd") (width 0.05))
    (fp_line (start 0.9 -1.3) (end -0.9 -1.3) (layer "B.CrtYd") (width 0.05))
    (fp_line (start 1.4 0.4) (end 1.4 -0.4) (layer "B.CrtYd") (width 0.05))
    (fp_line (start -0.9 1.3) (end 0.9 1.3) (layer "B.CrtYd") (width 0.05))
    (fp_line (start -0.9 1.3) (end -0.9 1) (layer "B.CrtYd") (width 0.05))
    (fp_line (start -0.9 1) (end -1.4 1) (layer "B.CrtYd") (width 0.05))
    (fp_line (start 0.9 0.4) (end 1.4 0.4) (layer "B.CrtYd") (width 0.05))
    (fp_line (start -0.9 -1) (end -1.4 -1) (layer "B.CrtYd") (width 0.05))
    (fp_line (start 1.4 -0.4) (end 0.9 -0.4) (layer "B.CrtYd") (width 0.05))
    (fp_line (start -0.9 -1.3) (end -0.9 -1) (layer "B.CrtYd") (width 0.05))
    (fp_line (start 0.9 1.3) (end 0.9 0.4) (layer "B.CrtYd") (width 0.05))
    (fp_rect (start -0.623 0.999) (end 0.627 -1.001) (layer "B.Fab") (width 0.15) (fill none))
    (pad "1" smd rect (at -1.051 0.65 270) (size 0.6 0.6) (layers "B.Cu" "B.Paste" "B.Mask")
      (net 132 "VREG_S4A_1V8") (pinfunction "G") (pintype "bidirectional"))
    (pad "2" smd rect (at -1.051 -0.65 270) (size 0.6 0.6) (layers "B.Cu" "B.Paste" "B.Mask")
      (net 35 "LT9611_GPIO5") (pinfunction "S") (pintype "bidirectional"))
    (pad "3" smd rect (at 1.05 0 270) (size 0.6 0.6) (layers "B.Cu" "B.Paste" "B.Mask")
      (net 284 "/HDMI converter/LT9611_INTO_GPIO5") (pinfunction "D") (pintype "bidirectional"))
  )
	(footprint "sa800u-baseboard-hw-footprints:SC70-3" (layer "B.Cu")
    (tedit 615FF353)
    (at 118.8 116.2)
    (property "Author" "Antmicro")
    (property "License" "Apache-2.0")
    (property "MPN" "BSS138PW")
    (property "Manufacturer" "Nexperia")
    (property "Sheetfile" "hdmi-converter.kicad_sch")
    (property "Sheetname" "HDMI converter")
    (attr smd)
    (fp_text reference "Q2" (at 0.59 1.95 180) (layer "B.SilkS")
      (effects (font (size 0.7 0.7) (thickness 0.15)) (justify left bottom mirror))
    )
    (fp_text value "BSS138PW" (at 0 -2.3 180) (layer "B.Fab")
      (effects (font (size 0.7 0.7) (thickness 0.15)) (justify left bottom mirror))
    )
    (fp_text user "Author: Antmicro" (at -1.45 -5.782 180) (layer "B.Fab") hide
      (effects (font (size 0.7 0.7) (thickness 0.15)) (justify left bottom mirror))
    )
    (fp_text user "License: Apache-2.0" (at -1.45 -6.782 180) (layer "B.Fab") hide
      (effects (font (size 0.7 0.7) (thickness 0.15)) (justify left bottom mirror))
    )
    (fp_text user "${REFERENCE}" (at -1.45 -4.783 180) (layer "B.Fab") hide
      (effects (font (size 0.7 0.7) (thickness 0.15)) (justify left bottom mirror))
    )
    (fp_line (start -0.3 1) (end 0.627 0.999) (layer "B.SilkS") (width 0.15))
    (fp_line (start 0.627 -0.6) (end 0.627 -1.001) (layer "B.SilkS") (width 0.15))
    (fp_line (start -0.3 -1) (end 0.627 -1.001) (layer "B.SilkS") (width 0.15))
    (fp_line (start 0.627 0.6) (end 0.627 0.999) (layer "B.SilkS") (width 0.15))
    (fp_line (start 1.4 0.4) (end 1.4 -0.4) (layer "B.CrtYd") (width 0.05))
    (fp_line (start 0.9 -0.4) (end 0.9 -1.3) (layer "B.CrtYd") (width 0.05))
    (fp_line (start -0.9 -1.3) (end -0.9 -1) (layer "B.CrtYd") (width 0.05))
    (fp_line (start -0.9 1) (end -1.4 1) (layer "B.CrtYd") (width 0.05))
    (fp_line (start -0.9 1.3) (end -0.9 1) (layer "B.CrtYd") (width 0.05))
    (fp_line (start 1.4 -0.4) (end 0.9 -0.4) (layer "B.CrtYd") (width 0.05))
    (fp_line (start -0.9 -1) (end -1.4 -1) (layer "B.CrtYd") (width 0.05))
    (fp_line (start -1.4 -1) (end -1.4 1) (layer "B.CrtYd") (width 0.05))
    (fp_line (start 0.9 -1.3) (end -0.9 -1.3) (layer "B.CrtYd") (width 0.05))
    (fp_line (start 0.9 0.4) (end 1.4 0.4) (layer "B.CrtYd") (width 0.05))
    (fp_line (start -0.9 1.3) (end 0.9 1.3) (layer "B.CrtYd") (width 0.05))
    (fp_line (start 0.9 1.3) (end 0.9 0.4) (layer "B.CrtYd") (width 0.05))
    (fp_rect (start -0.623 0.999) (end 0.627 -1.001) (layer "B.Fab") (width 0.15) (fill none))
    (pad "1" smd rect (at -1.051 0.65 270) (size 0.6 0.6) (layers "B.Cu" "B.Paste" "B.Mask")
      (net 132 "VREG_S4A_1V8") (pinfunction "G") (pintype "bidirectional"))
    (pad "2" smd rect (at -1.051 -0.65 270) (size 0.6 0.6) (layers "B.Cu" "B.Paste" "B.Mask")
      (net 36 "LT9611_RST") (pinfunction "S") (pintype "bidirectional"))
    (pad "3" smd rect (at 1.05 0 270) (size 0.6 0.6) (layers "B.Cu" "B.Paste" "B.Mask")
      (net 186 "/HDMI converter/LT9611_RST_N") (pinfunction "D") (pintype "bidirectional"))
  )
)
